# T6G (Grand Teton) — schematic netlist excerpt (pin names and nets, part order shuffled) for the footprints in the layout excerpt that follows; sources: Cadence DE-HDL packaged netlist, KiCad conversion of 04192023_DAF0TMB3IC0_F0TG_MB_C_brd_V02_OCP.brd

PC109  Q_CAP  2.2UF 10V 10% X6S  pkg C0402  page 202 : A = PVDDCR_CPU1_P0_VCC4 ; B = GND
R3583  Q_RES  2.2K 5% CHIP  pkg 0402LF  page 250 : A = P3V3_AUX ; B = SMB_IOEXP_3V3AUX_SDA

(kicad_pcb
	(version 20260206)
	(generator "pcbnew")
	(generator_version "10.0")
	(general
		(thickness 1.6)
		(legacy_teardrops no)
	)
	(paper "A4")
	(title_block
		(title "04192023_DAF0TMB3IC0_F0TG_MB_C_brd_V02_OCP.brd")
		(comment 1 "Grand Teton / footprints 2473-2474 of 8354")
	)
	(layers
		(0 "F.Cu" signal "TOP")
		(4 "In1.Cu" signal "GND")
		(6 "In2.Cu" signal "IN1")
		(8 "In3.Cu" signal "GND1")
		(10 "In4.Cu" signal "IN2")
		(12 "In5.Cu" signal "GND2")
		(14 "In6.Cu" signal "IN3")
		(16 "In7.Cu" signal "GND3")
		(18 "In8.Cu" signal "VCC")
		(20 "In9.Cu" signal "VCC1")
		(22 "In10.Cu" signal "GND4")
		(24 "In11.Cu" signal "IN4")
		(26 "In12.Cu" signal "GND5")
		(28 "In13.Cu" signal "IN5")
		(30 "In14.Cu" signal "GND6")
		(32 "In15.Cu" signal "IN6")
		(34 "In16.Cu" signal "GND7")
		(2 "B.Cu" signal "BOTTOM")
		(9 "F.Adhes" user "F.Adhesive")
		(11 "B.Adhes" user "B.Adhesive")
		(13 "F.Paste" user "Package Geometry/Pastemask Top")
		(15 "B.Paste" user "Package Geometry/Pastemask Bottom")
		(5 "F.SilkS" user "Ref Des/Silkscreen Top")
		(7 "B.SilkS" user "Ref Des/Silkscreen Bottom")
		(1 "F.Mask" user "Board Geometry/Soldermask Top")
		(3 "B.Mask" user "Board Geometry/Soldermask Bottom")
		(17 "Dwgs.User" user "User.Drawings")
		(19 "Cmts.User" user "User.Comments")
		(21 "Eco1.User" user "User.Eco1")
		(23 "Eco2.User" user "User.Eco2")
		(25 "Edge.Cuts" user "Board Geometry/Outline")
		(27 "Margin" user)
		(31 "F.CrtYd" user "Package Geometry/Place Bound Top")
		(29 "B.CrtYd" user "Package Geometry/Place Bound Bottom")
		(35 "F.Fab" user "Ref Des/Assembly Top")
		(33 "B.Fab" user "Ref Des/Assembly Bottom")
	)
	(footprint ""
		(layer "F.Cu")
		(at 305.013106 -349.381572 90)
		(property "Reference" "PC109"
			(at 0 0 90)
			(layer "F.SilkS")
			(hide yes)
			(effects
				(font
					(size 1.27 1.27)
				)
			)
		)
		(property "Value" ""
			(at 0 0 90)
			(layer "F.Fab")
			(effects
				(font
					(size 1.27 1.27)
				)
			)
		)
		(duplicate_pad_numbers_are_jumpers no)
		(fp_line
			(start 0.7874 -0.4064)
			(end 0.7874 0.4064)
			(stroke
				(width 0.1524)
				(type default)
			)
			(layer "F.SilkS")
		)
		(fp_line
			(start -0.7874 -0.4064)
			(end 0.7874 -0.4064)
			(stroke
				(width 0.1524)
				(type default)
			)
			(layer "F.SilkS")
		)
		(fp_line
			(start 0.7874 0.4064)
			(end 0.376428 0.4064)
			(stroke
				(width 0.1524)
				(type default)
			)
			(layer "F.SilkS")
		)
		(fp_line
			(start -0.156972 0.4064)
			(end -0.7874 0.4064)
			(stroke
				(width 0.1524)
				(type default)
			)
			(layer "F.SilkS")
		)
		(fp_line
			(start -0.7874 0.4064)
			(end -0.7874 -0.4064)
			(stroke
				(width 0.1524)
				(type default)
			)
			(layer "F.SilkS")
		)
		(fp_line
			(start -0.12065 -0.305054)
			(end -0.12065 -0.2794)
			(stroke
				(width 0.1)
				(type default)
			)
			(layer "F.Fab")
		)
		(fp_line
			(start -0.67945 -0.305054)
			(end -0.12065 -0.305054)
			(stroke
				(width 0.1)
				(type default)
			)
			(layer "F.Fab")
		)
		(fp_line
			(start 0.67945 -0.3048)
			(end 0.67945 0.3048)
			(stroke
				(width 0.1)
				(type default)
			)
			(layer "F.Fab")
		)
		(fp_line
			(start 0.12065 -0.3048)
			(end 0.67945 -0.3048)
			(stroke
				(width 0.1)
				(type default)
			)
			(layer "F.Fab")
		)
		(fp_line
			(start 0.12065 -0.2794)
			(end 0.12065 -0.3048)
			(stroke
				(width 0.1)
				(type default)
			)
			(layer "F.Fab")
		)
		(fp_line
			(start -0.12065 -0.2794)
			(end 0.12065 -0.2794)
			(stroke
				(width 0.1)
				(type default)
			)
			(layer "F.Fab")
		)
		(fp_line
			(start 0.120396 0.2794)
			(end -0.12065 0.2794)
			(stroke
				(width 0.1)
				(type default)
			)
			(layer "F.Fab")
		)
		(fp_line
			(start -0.12065 0.2794)
			(end -0.12065 0.3048)
			(stroke
				(width 0.1)
				(type default)
			)
			(layer "F.Fab")
		)
		(fp_line
			(start 0.67945 0.3048)
			(end 0.120396 0.3048)
			(stroke
				(width 0.1)
				(type default)
			)
			(layer "F.Fab")
		)
		(fp_line
			(start 0.120396 0.3048)
			(end 0.120396 0.2794)
			(stroke
				(width 0.1)
				(type default)
			)
			(layer "F.Fab")
		)
		(fp_line
			(start -0.12065 0.3048)
			(end -0.67945 0.3048)
			(stroke
				(width 0.1)
				(type default)
			)
			(layer "F.Fab")
		)
		(fp_line
			(start -0.67945 0.3048)
			(end -0.67945 -0.305054)
			(stroke
				(width 0.1)
				(type default)
			)
			(layer "F.Fab")
		)
		(pad "1" smd circle
			(at -0.40005 0 90)
			(size 0 0)
			(layers "F.Cu" "F.Mask" "F.Paste")
			(net "PVDDCR_CPU1_P0_VCC4")
		)
		(pad "2" smd circle
			(at 0.40005 0 90)
			(size 0 0)
			(layers "F.Cu" "F.Mask" "F.Paste")
			(net "GND")
		)
	)
	(footprint ""
		(layer "F.Cu")
		(at 277.352252 -118.89867)
		(property "Reference" "R3583"
			(at 0 0 0)
			(layer "F.SilkS")
			(hide yes)
			(effects
				(font
					(size 1.27 1.27)
				)
			)
		)
		(property "Value" ""
			(at 0 0 0)
			(layer "F.Fab")
			(effects
				(font
					(size 1.27 1.27)
				)
			)
		)
		(duplicate_pad_numbers_are_jumpers no)
		(fp_line
			(start -0.7874 -0.4064)
			(end 0.7874 -0.4064)
			(stroke
				(width 0.1524)
				(type default)
			)
			(layer "F.SilkS")
		)
		(fp_line
			(start -0.7874 0.4064)
			(end -0.7874 -0.4064)
			(stroke
				(width 0.1524)
				(type default)
			)
			(layer "F.SilkS")
		)
		(fp_line
			(start 0.7874 -0.4064)
			(end 0.7874 0.4064)
			(stroke
				(width 0.1524)
				(type default)
			)
			(layer "F.SilkS")
		)
		(fp_line
			(start 0.7874 0.4064)
			(end -0.7874 0.4064)
			(stroke
				(width 0.1524)
				(type default)
			)
			(layer "F.SilkS")
		)
		(fp_line
			(start -0.67945 -0.305054)
			(end -0.12065 -0.305054)
			(stroke
				(width 0.1)
				(type default)
			)
			(layer "F.Fab")
		)
		(fp_line
			(start -0.67945 0.3048)
			(end -0.67945 -0.305054)
			(stroke
				(width 0.1)
				(type default)
			)
			(layer "F.Fab")
		)
		(fp_line
			(start -0.12065 -0.305054)
			(end -0.12065 -0.2794)
			(stroke
				(width 0.1)
				(type default)
			)
			(layer "F.Fab")
		)
		(fp_line
			(start -0.12065 -0.2794)
			(end 0.12065 -0.2794)
			(stroke
				(width 0.1)
				(type default)
			)
			(layer "F.Fab")
		)
		(fp_line
			(start -0.12065 0.2794)
			(end -0.12065 0.3048)
			(stroke
				(width 0.1)
				(type default)
			)
			(layer "F.Fab")
		)
		(fp_line
			(start -0.12065 0.3048)
			(end -0.67945 0.3048)
			(stroke
				(width 0.1)
				(type default)
			)
			(layer "F.Fab")
		)
		(fp_line
			(start 0.120396 0.2794)
			(end -0.12065 0.2794)
			(stroke
				(width 0.1)
				(type default)
			)
			(layer "F.Fab")
		)
		(fp_line
			(start 0.120396 0.3048)
			(end 0.120396 0.2794)
			(stroke
				(width 0.1)
				(type default)
			)
			(layer "F.Fab")
		)
		(fp_line
			(start 0.12065 -0.3048)
			(end 0.67945 -0.3048)
			(stroke
				(width 0.1)
				(type default)
			)
			(layer "F.Fab")
		)
		(fp_line
			(start 0.12065 -0.2794)
			(end 0.12065 -0.3048)
			(stroke
				(width 0.1)
				(type default)
			)
			(layer "F.Fab")
		)
		(fp_line
			(start 0.67945 -0.3048)
			(end 0.67945 0.3048)
			(stroke
				(width 0.1)
				(type default)
			)
			(layer "F.Fab")
		)
		(fp_line
			(start 0.67945 0.3048)
			(end 0.120396 0.3048)
			(stroke
				(width 0.1)
				(type default)
			)
			(layer "F.Fab")
		)
		(pad "1" smd circle
			(at -0.40005 0)
			(size 0 0)
			(layers "F.Cu" "F.Mask" "F.Paste")
			(net "P3V3_AUX")
		)
		(pad "2" smd circle
			(at 0.40005 0)
			(size 0 0)
			(layers "F.Cu" "F.Mask" "F.Paste")
			(net "SMB_IOEXP_3V3AUX_SDA")
		)
	)
)
